( ConstraintFile "gnd"
	( constraintHeader
		( objectKey
			( logical )
		)
		( version
			( 16.6 )
		)
		( revisionNumber
			( logicalViewRevNum 3 )
			( physicalViewRevNum 0 )
			( otherViewRevNum 0 )
		)
		( contents
			( dictionaryExtensions )
			( worksheetCustomizations )
			( electricalConstraints )
			( netClasses )
			( properties )
		)
		( precision
			( units mil )
			( numberOfDecimalPlaces 2 )
		)
	)
	( DictionaryExtensions
		( Attribute
			( Name "MATERIAL" )
			( Description " " )
			( Value
				( DataType ( dString ) )
				( Status  sProperty  sPackage )
			)
			( Objects
				( ValidObjects  oGate  oGateDefn  oBlock  oPart  oDesign  oSystem  oPartDefn )
				( NoInherit
					( oGate oPin )
				)
			)
			( Analysis
			)
		)
		( Attribute
			( Name "TOLERANCE" )
			( Description " " )
			( Value
				( DataType ( dString ) )
				( Status  sProperty  sPackage )
			)
			( Objects
				( ValidObjects  oGate  oGateDefn  oBlock  oPart  oDesign  oSystem  oPartDefn )
				( NoInherit
					( oGate oPin )
				)
			)
			( Analysis
			)
		)
		( Attribute
			( Name "WATTAGE" )
			( Description " " )
			( Value
				( DataType ( dString ) )
				( Status  sProperty  sPackage )
			)
			( Objects
				( ValidObjects  oGate  oGateDefn  oBlock  oPart  oDesign  oSystem  oPartDefn )
				( NoInherit
					( oGate oPin )
				)
			)
			( Analysis
			)
		)
		( Attribute
			( Name "BOM_COST" )
			( Description " " )
			( Value
				( DataType ( dString ) )
				( Status  sProperty  sPackage )
			)
			( Objects
				( ValidObjects  oGate  oBlock  oPart  oDesign  oSystem  oGateDefn  oPartDefn )
				( NoInherit
					( oGate oPin )
				)
			)
			( Analysis
			)
		)
		( Attribute
			( Name "SKT_NUMBER" )
			( Description " " )
			( Value
				( DataType ( dString ) )
				( Status  sProperty  sPackage )
			)
			( Objects
				( ValidObjects  oGate  oBlock  oPart  oDesign  oSystem  oGateDefn  oPartDefn )
				( NoInherit
					( oGate oPin )
				)
			)
			( Analysis
			)
		)
	)
	( designConstraints
		( ruleChanges
			( allRules )
			( design "gnd"
				( attribute "CDS_DRAWING_BODY_PAGE" "1"
					( Origin gPackager )
				)
			)
			( signal "@mstr_symbols.gnd(sch_1):gnd"
				( alias ( signalRef "@mstr_symbols.gnd(sch_1):page1_gnd") )
				( alias ( signalRef "@mstr_symbols.gnd(sch_1):page1_a") )
				( alias ( signalRef "@mstr_symbols.gnd(sch_1):a") )
				( objectStatus "gnd" )
			)
			( signal "@mstr_symbols.gnd(sch_1):page1_a"
				( objectFlag fObjectAlias )
				( objectStatus "page1_a" )
			)
			( signal "@mstr_symbols.gnd(sch_1):a"
				( objectFlag fObjectAlias )
				( objectStatus "a" )
			)
			( signal "@mstr_symbols.gnd(sch_1):page1_gnd"
				( objectFlag fObjectAlias )
				( objectStatus "page1_gnd" )
			)
		)
	)
)
